# TIMECARD (Time Appliance Project (Time Card)) — schematic netlist excerpt (pin names and nets, part order shuffled) for the footprints in the layout excerpt that follows; sources: Cadence DE-HDL packaged netlist, KiCad conversion of R4006-B0001-02_R01.brd

C232  CAPACITOR  22UF 10V 20%  pkg SMC_0805R_H057  page 31 : \1\ = XP3R3V ; \2\ = SG
DS10  OPTICAL  pkg SMC_DS_063X031_V4  page 26 : A = UNNAMED_14_OPTICAL_I138_A ; C = FPGA_USR_LED1

(kicad_pcb
	(version 20260206)
	(generator "pcbnew")
	(generator_version "10.0")
	(general
		(thickness 1.6)
		(legacy_teardrops no)
	)
	(paper "A4")
	(title_block
		(title "timecard-production-celestica-r4006 — R4006-B0001-02_R01.brd")
		(comment 1 "Time Appliance Project (Time Card) / footprints 248-249 of 1113")
	)
	(layers
		(0 "F.Cu" signal "TOP")
		(4 "In1.Cu" signal "L02_GND1")
		(6 "In2.Cu" signal "L03_SIG1")
		(8 "In3.Cu" signal "L04_GND2")
		(10 "In4.Cu" signal "L05_VCC1")
		(12 "In5.Cu" signal "L06_VCC2")
		(14 "In6.Cu" signal "L07_GND3")
		(16 "In7.Cu" signal "L08_SIG2")
		(18 "In8.Cu" signal "L09_GND4")
		(2 "B.Cu" signal "BOTTOM")
		(9 "F.Adhes" user "F.Adhesive")
		(11 "B.Adhes" user "B.Adhesive")
		(13 "F.Paste" user "Package Geometry/Pastemask Top")
		(15 "B.Paste" user "Package Geometry/Pastemask Bottom")
		(5 "F.SilkS" user "Ref Des/Silkscreen Top")
		(7 "B.SilkS" user "Ref Des/Silkscreen Bottom")
		(1 "F.Mask" user "Board Geometry/Soldermask Top")
		(3 "B.Mask" user "Board Geometry/Soldermask Bottom")
		(17 "Dwgs.User" user "User.Drawings")
		(19 "Cmts.User" user "User.Comments")
		(21 "Eco1.User" user "User.Eco1")
		(23 "Eco2.User" user "User.Eco2")
		(25 "Edge.Cuts" user "Board Geometry/Outline")
		(27 "Margin" user)
		(31 "F.CrtYd" user "Package Geometry/Place Bound Top")
		(29 "B.CrtYd" user "Package Geometry/Place Bound Bottom")
		(35 "F.Fab" user "Ref Des/Assembly Top")
		(33 "B.Fab" user "Ref Des/Assembly Bottom")
	)
	(footprint ""
		(layer "F.Cu")
		(at 153.049986 -107.849924 -90)
		(property "Reference" "DS10"
			(at 0.026924 -1.421384 90)
			(unlocked yes)
			(layer "F.SilkS")
			(effects
				(font
					(size 0.7874 0.5842)
					(thickness 0.1524)
				)
			)
		)
		(property "Value" ""
			(at 0 0 270)
			(layer "F.Fab")
			(effects
				(font
					(size 1.27 1.27)
				)
			)
		)
		(property "Device Type" "OPTICAL-G170-10143-01"
			(at 0.1778 1.483081 270)
			(unlocked yes)
			(layer "F.Fab")
			(hide yes)
			(effects
				(font
					(size 0.786892 0.583946)
					(thickness 0.000001)
				)
			)
		)
		(property "User Part Number" "PARTNUM*"
			(at 0.1778 2.422881 270)
			(unlocked yes)
			(layer "Cmts.User")
			(hide yes)
			(effects
				(font
					(size 0.786892 0.583946)
					(thickness 0.000001)
				)
			)
		)
		(duplicate_pad_numbers_are_jumpers no)
		(fp_line
			(start -1.1938 1.0922)
			(end -2.4638 1.0922)
			(stroke
				(width 0.1)
				(type default)
			)
			(layer "F.SilkS")
		)
		(fp_line
			(start -1.397508 0.704088)
			(end -1.397508 -0.704088)
			(stroke
				(width 0.1)
				(type default)
			)
			(layer "F.SilkS")
		)
		(fp_line
			(start 1.397508 0.704088)
			(end -1.397508 0.704088)
			(stroke
				(width 0.1)
				(type default)
			)
			(layer "F.SilkS")
		)
		(fp_line
			(start -1.8288 0.4572)
			(end -1.8288 1.7272)
			(stroke
				(width 0.1)
				(type default)
			)
			(layer "F.SilkS")
		)
		(fp_line
			(start -1.397508 -0.704088)
			(end 1.397508 -0.704088)
			(stroke
				(width 0.1)
				(type default)
			)
			(layer "F.SilkS")
		)
		(fp_line
			(start 1.397508 -0.704088)
			(end 1.397508 0.704088)
			(stroke
				(width 0.1)
				(type default)
			)
			(layer "F.SilkS")
		)
		(fp_rect
			(start 1.905508 0.704088)
			(end 1.397508 -0.704088)
			(stroke
				(width 0)
				(type default)
			)
			(fill yes)
			(layer "F.SilkS")
		)
		(fp_rect
			(start 1.905508 0.958088)
			(end -1.651508 -0.958088)
			(stroke
				(width 0)
				(type default)
			)
			(fill no)
			(layer "F.CrtYd")
		)
		(fp_line
			(start -1.0668 1.2192)
			(end -2.3368 1.2192)
			(stroke
				(width 0.1)
				(type default)
			)
			(layer "F.Fab")
		)
		(fp_line
			(start -1.7018 0.5842)
			(end -1.7018 1.8542)
			(stroke
				(width 0.1)
				(type default)
			)
			(layer "F.Fab")
		)
		(fp_line
			(start -0.850138 0.450088)
			(end 0.850138 0.450088)
			(stroke
				(width 0.1)
				(type default)
			)
			(layer "F.Fab")
		)
		(fp_line
			(start 0.850138 0.450088)
			(end 0.850138 -0.450088)
			(stroke
				(width 0.1)
				(type default)
			)
			(layer "F.Fab")
		)
		(fp_line
			(start -0.850138 -0.450088)
			(end -0.850138 0.450088)
			(stroke
				(width 0.1)
				(type default)
			)
			(layer "F.Fab")
		)
		(fp_line
			(start 0.850138 -0.450088)
			(end -0.850138 -0.450088)
			(stroke
				(width 0.1)
				(type default)
			)
			(layer "F.Fab")
		)
		(fp_rect
			(start 0.850138 0.450088)
			(end 0.342138 -0.450088)
			(stroke
				(width 0)
				(type default)
			)
			(fill yes)
			(layer "F.Fab")
		)
		(fp_text user "C"
			(at 1.404874 1.284986 0)
			(unlocked yes)
			(layer "F.SilkS")
			(effects
				(font
					(size 0.635 0.4064)
					(thickness 0.1524)
				)
			)
		)
		(fp_text user "A"
			(at -1.846326 0.014986 0)
			(unlocked yes)
			(layer "F.SilkS")
			(effects
				(font
					(size 0.635 0.4064)
					(thickness 0.1524)
				)
			)
		)
		(fp_text user "A"
			(at -2.346706 0.141986 0)
			(unlocked yes)
			(layer "F.Fab")
			(effects
				(font
					(size 0.7874 0.5842)
					(thickness 0.1524)
				)
			)
		)
		(fp_text user "C"
			(at 0.828294 -1.001014 0)
			(unlocked yes)
			(layer "F.Fab")
			(effects
				(font
					(size 0.7874 0.5842)
					(thickness 0.1524)
				)
			)
		)
		(pad "A" smd rect
			(at -0.749808 0 270)
			(size 0.7874 0.7874)
			(layers "F.Cu" "F.Mask" "F.Paste")
			(net "UNNAMED_14_OPTICAL_I138_A")
		)
		(pad "C" smd rect
			(at 0.749808 0 270)
			(size 0.7874 0.7874)
			(layers "F.Cu" "F.Mask" "F.Paste")
			(net "FPGA_USR_LED1")
		)
	)
	(footprint ""
		(layer "F.Cu")
		(at 113.157 -68.707 -90)
		(property "Reference" "C232"
			(at -0.381 -2.96037 90)
			(unlocked yes)
			(layer "F.SilkS")
			(effects
				(font
					(size 0.7874 0.5842)
					(thickness 0.1524)
				)
			)
		)
		(property "Value" "VAL*"
			(at 0.0762 3.134106 270)
			(unlocked yes)
			(layer "F.Fab")
			(hide yes)
			(effects
				(font
					(size 0.7874 0.5842)
					(thickness 0.1524)
				)
			)
		)
		(property "Tolerance" "TOL*"
			(at 0.0762 4.048506 270)
			(unlocked yes)
			(layer "Cmts.User")
			(hide yes)
			(effects
				(font
					(size 0.7874 0.5842)
					(thickness 0.1524)
				)
			)
		)
		(property "User Part Number" "PARTNUM*"
			(at 0.1016 5.013706 270)
			(unlocked yes)
			(layer "Cmts.User")
			(hide yes)
			(effects
				(font
					(size 0.7874 0.5842)
					(thickness 0.1524)
				)
			)
		)
		(property "Device Type" "CAPACITOR-G107-0F226-CM,22UF,2A"
			(at 0.0508 2.194306 270)
			(unlocked yes)
			(layer "F.Fab")
			(hide yes)
			(effects
				(font
					(size 0.7874 0.5842)
					(thickness 0.1524)
				)
			)
		)
		(duplicate_pad_numbers_are_jumpers no)
		(fp_line
			(start -1.5748 0.9398)
			(end 1.5748 0.9398)
			(stroke
				(width 0.1)
				(type default)
			)
			(layer "F.SilkS")
		)
		(fp_line
			(start 1.5748 0.9398)
			(end 1.5748 -0.9398)
			(stroke
				(width 0.1)
				(type default)
			)
			(layer "F.SilkS")
		)
		(fp_line
			(start -1.5748 -0.9398)
			(end -1.5748 0.9398)
			(stroke
				(width 0.1)
				(type default)
			)
			(layer "F.SilkS")
		)
		(fp_line
			(start 1.5748 -0.9398)
			(end -1.5748 -0.9398)
			(stroke
				(width 0.1)
				(type default)
			)
			(layer "F.SilkS")
		)
		(fp_rect
			(start 1.5748 -0.9398)
			(end -1.5748 0.9398)
			(stroke
				(width 0)
				(type default)
			)
			(fill no)
			(layer "F.CrtYd")
		)
		(fp_line
			(start -1.016 0.635)
			(end 1.016 0.635)
			(stroke
				(width 0.1)
				(type default)
			)
			(layer "F.Fab")
		)
		(fp_line
			(start 1.016 0.635)
			(end 1.016 -0.635)
			(stroke
				(width 0.1)
				(type default)
			)
			(layer "F.Fab")
		)
		(fp_line
			(start -1.016 -0.635)
			(end -1.016 0.635)
			(stroke
				(width 0.1)
				(type default)
			)
			(layer "F.Fab")
		)
		(fp_line
			(start 1.016 -0.635)
			(end -1.016 -0.635)
			(stroke
				(width 0.1)
				(type default)
			)
			(layer "F.Fab")
		)
		(pad "1" smd rect
			(at -0.8382 0 270)
			(size 0.9652 1.3716)
			(layers "F.Cu" "F.Mask" "F.Paste")
			(net "XP3R3V")
		)
		(pad "2" smd rect
			(at 0.8382 0 270)
			(size 0.9652 1.3716)
			(layers "F.Cu" "F.Mask" "F.Paste")
			(net "SG")
		)
		(zone
			(layer "F.Cu")
			(hatch none 0.5)
			(connect_pads
				(clearance 0)
			)
			(min_thickness 0.25)
			(keepout
				(tracks allowed)
				(vias not_allowed)
				(pads allowed)
				(copperpour not_allowed)
				(footprints allowed)
			)
			(placement
				(enabled no)
				(sheetname "")
			)
			(fill
				(thermal_gap 0.5)
				(thermal_bridge_width 0.5)
				(island_removal_mode 0)
			)
			(polygon
				(pts
					(xy 113.792 -68.4784) (xy 113.792 -68.9356) (xy 112.522 -68.9356) (xy 112.522 -68.4784)
				)
			)
		)
	)
)
